# T6G (Grand Teton) — schematic netlist excerpt (pin names and nets, part order shuffled) for the footprints in the layout excerpt that follows; sources: Cadence DE-HDL packaged netlist, KiCad conversion of 04192023_DAF0TMB3IC0_F0TG_MB_C_brd_V02_OCP.brd

R2789  Q_RES  0 5% EMPTY  pkg 0402LF  page 234 : A = USB2_HOST_BMC_B_BUF_DN ; B = USB2_HUB_BUF_SWB_R_DN
C1809  Q_CAP  0.1UF 25V 10% X7R  pkg 0402  page 140 : A = P3V3_AUX ; B = GND

(kicad_pcb
	(version 20260206)
	(generator "pcbnew")
	(generator_version "10.0")
	(general
		(thickness 1.6)
		(legacy_teardrops no)
	)
	(paper "A4")
	(title_block
		(title "04192023_DAF0TMB3IC0_F0TG_MB_C_brd_V02_OCP.brd")
		(comment 1 "Grand Teton / footprints 1424-1425 of 8354")
	)
	(layers
		(0 "F.Cu" signal "TOP")
		(4 "In1.Cu" signal "GND")
		(6 "In2.Cu" signal "IN1")
		(8 "In3.Cu" signal "GND1")
		(10 "In4.Cu" signal "IN2")
		(12 "In5.Cu" signal "GND2")
		(14 "In6.Cu" signal "IN3")
		(16 "In7.Cu" signal "GND3")
		(18 "In8.Cu" signal "VCC")
		(20 "In9.Cu" signal "VCC1")
		(22 "In10.Cu" signal "GND4")
		(24 "In11.Cu" signal "IN4")
		(26 "In12.Cu" signal "GND5")
		(28 "In13.Cu" signal "IN5")
		(30 "In14.Cu" signal "GND6")
		(32 "In15.Cu" signal "IN6")
		(34 "In16.Cu" signal "GND7")
		(2 "B.Cu" signal "BOTTOM")
		(9 "F.Adhes" user "F.Adhesive")
		(11 "B.Adhes" user "B.Adhesive")
		(13 "F.Paste" user "Package Geometry/Pastemask Top")
		(15 "B.Paste" user "Package Geometry/Pastemask Bottom")
		(5 "F.SilkS" user "Ref Des/Silkscreen Top")
		(7 "B.SilkS" user "Ref Des/Silkscreen Bottom")
		(1 "F.Mask" user "Board Geometry/Soldermask Top")
		(3 "B.Mask" user "Board Geometry/Soldermask Bottom")
		(17 "Dwgs.User" user "User.Drawings")
		(19 "Cmts.User" user "User.Comments")
		(21 "Eco1.User" user "User.Eco1")
		(23 "Eco2.User" user "User.Eco2")
		(25 "Edge.Cuts" user "Board Geometry/Outline")
		(27 "Margin" user)
		(31 "F.CrtYd" user "Package Geometry/Place Bound Top")
		(29 "B.CrtYd" user "Package Geometry/Place Bound Bottom")
		(35 "F.Fab" user "Ref Des/Assembly Top")
		(33 "B.Fab" user "Ref Des/Assembly Bottom")
	)
	(footprint ""
		(layer "F.Cu")
		(at 15.58417 -78.830678)
		(property "Reference" "C1809"
			(at 0 0 0)
			(layer "F.SilkS")
			(hide yes)
			(effects
				(font
					(size 1.27 1.27)
				)
			)
		)
		(property "Value" ""
			(at 0 0 0)
			(layer "F.Fab")
			(effects
				(font
					(size 1.27 1.27)
				)
			)
		)
		(duplicate_pad_numbers_are_jumpers no)
		(fp_line
			(start -0.7874 -0.4064)
			(end 0.7874 -0.4064)
			(stroke
				(width 0.1524)
				(type default)
			)
			(layer "F.SilkS")
		)
		(fp_line
			(start -0.7874 0.4064)
			(end -0.7874 -0.4064)
			(stroke
				(width 0.1524)
				(type default)
			)
			(layer "F.SilkS")
		)
		(fp_line
			(start 0.7874 -0.4064)
			(end 0.7874 0.4064)
			(stroke
				(width 0.1524)
				(type default)
			)
			(layer "F.SilkS")
		)
		(fp_line
			(start 0.7874 0.4064)
			(end -0.7874 0.4064)
			(stroke
				(width 0.1524)
				(type default)
			)
			(layer "F.SilkS")
		)
		(fp_line
			(start -0.67945 -0.305054)
			(end -0.12065 -0.305054)
			(stroke
				(width 0.1)
				(type default)
			)
			(layer "F.Fab")
		)
		(fp_line
			(start -0.67945 0.3048)
			(end -0.67945 -0.305054)
			(stroke
				(width 0.1)
				(type default)
			)
			(layer "F.Fab")
		)
		(fp_line
			(start -0.12065 -0.305054)
			(end -0.12065 -0.2794)
			(stroke
				(width 0.1)
				(type default)
			)
			(layer "F.Fab")
		)
		(fp_line
			(start -0.12065 -0.2794)
			(end 0.12065 -0.2794)
			(stroke
				(width 0.1)
				(type default)
			)
			(layer "F.Fab")
		)
		(fp_line
			(start -0.12065 0.2794)
			(end -0.12065 0.3048)
			(stroke
				(width 0.1)
				(type default)
			)
			(layer "F.Fab")
		)
		(fp_line
			(start -0.12065 0.3048)
			(end -0.67945 0.3048)
			(stroke
				(width 0.1)
				(type default)
			)
			(layer "F.Fab")
		)
		(fp_line
			(start 0.120396 0.2794)
			(end -0.12065 0.2794)
			(stroke
				(width 0.1)
				(type default)
			)
			(layer "F.Fab")
		)
		(fp_line
			(start 0.120396 0.3048)
			(end 0.120396 0.2794)
			(stroke
				(width 0.1)
				(type default)
			)
			(layer "F.Fab")
		)
		(fp_line
			(start 0.12065 -0.3048)
			(end 0.67945 -0.3048)
			(stroke
				(width 0.1)
				(type default)
			)
			(layer "F.Fab")
		)
		(fp_line
			(start 0.12065 -0.2794)
			(end 0.12065 -0.3048)
			(stroke
				(width 0.1)
				(type default)
			)
			(layer "F.Fab")
		)
		(fp_line
			(start 0.67945 -0.3048)
			(end 0.67945 0.3048)
			(stroke
				(width 0.1)
				(type default)
			)
			(layer "F.Fab")
		)
		(fp_line
			(start 0.67945 0.3048)
			(end 0.120396 0.3048)
			(stroke
				(width 0.1)
				(type default)
			)
			(layer "F.Fab")
		)
		(pad "1" smd circle
			(at -0.40005 0)
			(size 0 0)
			(layers "F.Cu" "F.Mask" "F.Paste")
			(net "P3V3_AUX")
		)
		(pad "2" smd circle
			(at 0.40005 0)
			(size 0 0)
			(layers "F.Cu" "F.Mask" "F.Paste")
			(net "GND")
		)
	)
	(footprint ""
		(layer "F.Cu")
		(at 12.786106 -106.30408 -90)
		(property "Reference" "R2789"
			(at 0 0 270)
			(layer "F.SilkS")
			(hide yes)
			(effects
				(font
					(size 1.27 1.27)
				)
			)
		)
		(property "Value" ""
			(at 0 0 270)
			(layer "F.Fab")
			(effects
				(font
					(size 1.27 1.27)
				)
			)
		)
		(duplicate_pad_numbers_are_jumpers no)
		(fp_line
			(start -0.7874 0.4064)
			(end -0.7874 -0.4064)
			(stroke
				(width 0.1524)
				(type default)
			)
			(layer "F.SilkS")
		)
		(fp_line
			(start 0.7874 0.4064)
			(end -0.7874 0.4064)
			(stroke
				(width 0.1524)
				(type default)
			)
			(layer "F.SilkS")
		)
		(fp_line
			(start -0.7874 -0.4064)
			(end 0.7874 -0.4064)
			(stroke
				(width 0.1524)
				(type default)
			)
			(layer "F.SilkS")
		)
		(fp_line
			(start 0.7874 -0.4064)
			(end 0.7874 0.4064)
			(stroke
				(width 0.1524)
				(type default)
			)
			(layer "F.SilkS")
		)
		(fp_line
			(start -0.67945 0.3048)
			(end -0.67945 -0.305054)
			(stroke
				(width 0.1)
				(type default)
			)
			(layer "F.Fab")
		)
		(fp_line
			(start -0.12065 0.3048)
			(end -0.67945 0.3048)
			(stroke
				(width 0.1)
				(type default)
			)
			(layer "F.Fab")
		)
		(fp_line
			(start 0.120396 0.3048)
			(end 0.120396 0.2794)
			(stroke
				(width 0.1)
				(type default)
			)
			(layer "F.Fab")
		)
		(fp_line
			(start 0.67945 0.3048)
			(end 0.120396 0.3048)
			(stroke
				(width 0.1)
				(type default)
			)
			(layer "F.Fab")
		)
		(fp_line
			(start -0.12065 0.2794)
			(end -0.12065 0.3048)
			(stroke
				(width 0.1)
				(type default)
			)
			(layer "F.Fab")
		)
		(fp_line
			(start 0.120396 0.2794)
			(end -0.12065 0.2794)
			(stroke
				(width 0.1)
				(type default)
			)
			(layer "F.Fab")
		)
		(fp_line
			(start -0.12065 -0.2794)
			(end 0.12065 -0.2794)
			(stroke
				(width 0.1)
				(type default)
			)
			(layer "F.Fab")
		)
		(fp_line
			(start 0.12065 -0.2794)
			(end 0.12065 -0.3048)
			(stroke
				(width 0.1)
				(type default)
			)
			(layer "F.Fab")
		)
		(fp_line
			(start 0.12065 -0.3048)
			(end 0.67945 -0.3048)
			(stroke
				(width 0.1)
				(type default)
			)
			(layer "F.Fab")
		)
		(fp_line
			(start 0.67945 -0.3048)
			(end 0.67945 0.3048)
			(stroke
				(width 0.1)
				(type default)
			)
			(layer "F.Fab")
		)
		(fp_line
			(start -0.67945 -0.305054)
			(end -0.12065 -0.305054)
			(stroke
				(width 0.1)
				(type default)
			)
			(layer "F.Fab")
		)
		(fp_line
			(start -0.12065 -0.305054)
			(end -0.12065 -0.2794)
			(stroke
				(width 0.1)
				(type default)
			)
			(layer "F.Fab")
		)
		(pad "1" smd rect
			(at -0.40005 0 90)
			(size 0.4572 0.508)
			(layers "F.Cu" "F.Mask" "F.Paste")
			(net "USB2_HOST_BMC_B_BUF_DN")
		)
		(pad "2" smd rect
			(at 0.40005 0 90)
			(size 0.4572 0.508)
			(layers "F.Cu" "F.Mask" "F.Paste")
			(net "USB2_HUB_BUF_SWB_R_DN")
		)
	)
)
